# S9S_MB_2U (Grand Teton) — schematic netlist excerpt (pin names and nets, part order shuffled) for the footprints in the layout excerpt that follows; sources: Cadence DE-HDL packaged netlist, KiCad conversion of 03242023_DA0F0TMBIJ0_F0T_Motherboard_J_brd_V01_OCP.brd

R4199  Q_RES  1K 1% CHIP  pkg 0402LF  page 170 : A = U270_0_ADD1 ; B = GND
PL12  Q_INDUCTOR  130NH/106A IND  pkg SMLF  page 290 : \1\ = SW_PVCCFA_EHV_FIVRA_CPU1_SW3 ; \2\ = PVCCFA_EHV_FIVRA_CPU1
PC1645  Q_CAPP  560UF 2.5V 20% OSCON  pkg THLF  page 279 : A = PVCCD_HV_CPU0 ; B = GND

(kicad_pcb
	(version 20260206)
	(generator "pcbnew")
	(generator_version "10.0")
	(general
		(thickness 1.6)
		(legacy_teardrops no)
	)
	(paper "A4")
	(title_block
		(title "03242023_DA0F0TMBIJ0_F0T_Motherboard_J_brd_V01_OCP.brd")
		(comment 1 "Grand Teton / footprints 1298-1300 of 6105")
	)
	(layers
		(0 "F.Cu" signal "TOP")
		(4 "In1.Cu" signal "GND")
		(6 "In2.Cu" signal "IN1")
		(8 "In3.Cu" signal "GND1")
		(10 "In4.Cu" signal "IN2")
		(12 "In5.Cu" signal "GND2")
		(14 "In6.Cu" signal "IN3")
		(16 "In7.Cu" signal "GND3")
		(18 "In8.Cu" signal "VCC")
		(20 "In9.Cu" signal "VCC1")
		(22 "In10.Cu" signal "GND4")
		(24 "In11.Cu" signal "IN4")
		(26 "In12.Cu" signal "GND5")
		(28 "In13.Cu" signal "IN5")
		(30 "In14.Cu" signal "GND6")
		(32 "In15.Cu" signal "IN6")
		(34 "In16.Cu" signal "GND7")
		(2 "B.Cu" signal "BOTTOM")
		(9 "F.Adhes" user "F.Adhesive")
		(11 "B.Adhes" user "B.Adhesive")
		(13 "F.Paste" user "Package Geometry/Pastemask Top")
		(15 "B.Paste" user "Package Geometry/Pastemask Bottom")
		(5 "F.SilkS" user "Ref Des/Silkscreen Top")
		(7 "B.SilkS" user "Ref Des/Silkscreen Bottom")
		(1 "F.Mask" user "Board Geometry/Soldermask Top")
		(3 "B.Mask" user "Board Geometry/Soldermask Bottom")
		(17 "Dwgs.User" user "User.Drawings")
		(19 "Cmts.User" user "User.Comments")
		(21 "Eco1.User" user "User.Eco1")
		(23 "Eco2.User" user "User.Eco2")
		(25 "Edge.Cuts" user "Board Geometry/Outline")
		(27 "Margin" user)
		(31 "F.CrtYd" user "Package Geometry/Place Bound Top")
		(29 "B.CrtYd" user "Package Geometry/Place Bound Bottom")
		(35 "F.Fab" user "Ref Des/Assembly Top")
		(33 "B.Fab" user "Ref Des/Assembly Bottom")
	)
	(footprint ""
		(layer "F.Cu")
		(at 370.615718 -413.90443 -90)
		(property "Reference" "R4199"
			(at 0 0 270)
			(layer "F.SilkS")
			(hide yes)
			(effects
				(font
					(size 1.27 1.27)
				)
			)
		)
		(property "Value" ""
			(at 0 0 270)
			(layer "F.Fab")
			(effects
				(font
					(size 1.27 1.27)
				)
			)
		)
		(duplicate_pad_numbers_are_jumpers no)
		(fp_line
			(start -0.7874 0.4064)
			(end -0.7874 -0.4064)
			(stroke
				(width 0.1524)
				(type default)
			)
			(layer "F.SilkS")
		)
		(fp_line
			(start 0.7874 0.4064)
			(end -0.7874 0.4064)
			(stroke
				(width 0.1524)
				(type default)
			)
			(layer "F.SilkS")
		)
		(fp_line
			(start -0.7874 -0.4064)
			(end 0.7874 -0.4064)
			(stroke
				(width 0.1524)
				(type default)
			)
			(layer "F.SilkS")
		)
		(fp_line
			(start 0.7874 -0.4064)
			(end 0.7874 0.4064)
			(stroke
				(width 0.1524)
				(type default)
			)
			(layer "F.SilkS")
		)
		(fp_line
			(start -0.67945 0.3048)
			(end -0.67945 -0.305054)
			(stroke
				(width 0.1)
				(type default)
			)
			(layer "F.Fab")
		)
		(fp_line
			(start -0.12065 0.3048)
			(end -0.67945 0.3048)
			(stroke
				(width 0.1)
				(type default)
			)
			(layer "F.Fab")
		)
		(fp_line
			(start 0.120396 0.3048)
			(end 0.120396 0.2794)
			(stroke
				(width 0.1)
				(type default)
			)
			(layer "F.Fab")
		)
		(fp_line
			(start 0.67945 0.3048)
			(end 0.120396 0.3048)
			(stroke
				(width 0.1)
				(type default)
			)
			(layer "F.Fab")
		)
		(fp_line
			(start -0.12065 0.2794)
			(end -0.12065 0.3048)
			(stroke
				(width 0.1)
				(type default)
			)
			(layer "F.Fab")
		)
		(fp_line
			(start 0.120396 0.2794)
			(end -0.12065 0.2794)
			(stroke
				(width 0.1)
				(type default)
			)
			(layer "F.Fab")
		)
		(fp_line
			(start -0.12065 -0.2794)
			(end 0.12065 -0.2794)
			(stroke
				(width 0.1)
				(type default)
			)
			(layer "F.Fab")
		)
		(fp_line
			(start 0.12065 -0.2794)
			(end 0.12065 -0.3048)
			(stroke
				(width 0.1)
				(type default)
			)
			(layer "F.Fab")
		)
		(fp_line
			(start 0.12065 -0.3048)
			(end 0.67945 -0.3048)
			(stroke
				(width 0.1)
				(type default)
			)
			(layer "F.Fab")
		)
		(fp_line
			(start 0.67945 -0.3048)
			(end 0.67945 0.3048)
			(stroke
				(width 0.1)
				(type default)
			)
			(layer "F.Fab")
		)
		(fp_line
			(start -0.67945 -0.305054)
			(end -0.12065 -0.305054)
			(stroke
				(width 0.1)
				(type default)
			)
			(layer "F.Fab")
		)
		(fp_line
			(start -0.12065 -0.305054)
			(end -0.12065 -0.2794)
			(stroke
				(width 0.1)
				(type default)
			)
			(layer "F.Fab")
		)
		(pad "1" smd circle
			(at -0.40005 0 270)
			(size 0 0)
			(layers "F.Cu" "F.Mask" "F.Paste")
			(net "U270_0_ADD1")
		)
		(pad "2" smd circle
			(at 0.40005 0 270)
			(size 0 0)
			(layers "F.Cu" "F.Mask" "F.Paste")
			(net "GND")
		)
	)
	(footprint ""
		(layer "F.Cu")
		(at 400.558 -164.785548)
		(property "Reference" "PC1645"
			(at 0 0 0)
			(layer "F.SilkS")
			(hide yes)
			(effects
				(font
					(size 1.27 1.27)
				)
			)
		)
		(property "Value" ""
			(at 0 0 0)
			(layer "F.Fab")
			(effects
				(font
					(size 1.27 1.27)
				)
			)
		)
		(duplicate_pad_numbers_are_jumpers no)
		(fp_line
			(start 2.750058 0.999998)
			(end -2.750058 0.999998)
			(stroke
				(width 0.1524)
				(type default)
			)
			(layer "F.SilkS")
		)
		(fp_circle
			(center 0 0.999998)
			(end 2.750058 0.999998)
			(stroke
				(width 0.1524)
				(type default)
			)
			(fill no)
			(layer "F.SilkS")
		)
		(fp_poly
			(pts
				(arc
					(start 2.750058 0.999998)
					(mid 0 3.750056)
					(end -2.750058 0.999998)
				)
			)
			(stroke
				(width 0)
				(type default)
			)
			(fill yes)
			(layer "F.SilkS")
		)
		(fp_circle
			(center 0 0.999998)
			(end 2.750058 0.999998)
			(stroke
				(width 0.1)
				(type default)
			)
			(fill no)
			(layer "F.Fab")
		)
		(pad "1" thru_hole rect
			(at 0 0)
			(size 1.5748 1.5748)
			(drill 1.0668)
			(layers "*.Cu" "*.Mask")
			(remove_unused_layers no)
			(net "PVCCD_HV_CPU0")
			(clearance 0)
			(padstack
				(mode front_inner_back)
				(layer "Inner"
					(shape circle)
					(size 1.5748 1.5748)
					(clearance 0)
				)
				(layer "B.Cu"
					(shape rect)
					(size 1.5748 1.5748)
					(clearance 0)
				)
			)
		)
		(pad "2" thru_hole circle
			(at 0 1.999996)
			(size 1.5748 1.5748)
			(drill 1.0668)
			(layers "*.Cu" "*.Mask")
			(remove_unused_layers no)
			(net "GND")
			(clearance 0)
		)
	)
	(footprint ""
		(layer "F.Cu")
		(at 181.710584 -344.7796 -90)
		(property "Reference" "PL12"
			(at -3.214878 -4.197096 0)
			(unlocked yes)
			(layer "F.SilkS")
			(effects
				(font
					(size 0.7874 0.5842)
					(thickness 0.1524)
				)
				(justify left)
			)
		)
		(property "Value" ""
			(at 0 0 270)
			(layer "F.Fab")
			(effects
				(font
					(size 1.27 1.27)
				)
			)
		)
		(duplicate_pad_numbers_are_jumpers no)
		(fp_line
			(start -4.99999 3.750056)
			(end -4.99999 2.2479)
			(stroke
				(width 0.1524)
				(type default)
			)
			(layer "F.SilkS")
		)
		(fp_line
			(start 0 3.750056)
			(end -4.99999 3.750056)
			(stroke
				(width 0.1524)
				(type default)
			)
			(layer "F.SilkS")
		)
		(fp_line
			(start 4.99999 3.750056)
			(end 0 3.750056)
			(stroke
				(width 0.1524)
				(type default)
			)
			(layer "F.SilkS")
		)
		(fp_line
			(start 4.99999 2.2352)
			(end 4.99999 3.750056)
			(stroke
				(width 0.1524)
				(type default)
			)
			(layer "F.SilkS")
		)
		(fp_line
			(start -4.99999 -2.2479)
			(end -4.99999 -3.750056)
			(stroke
				(width 0.1524)
				(type default)
			)
			(layer "F.SilkS")
		)
		(fp_line
			(start -4.99999 -3.750056)
			(end 4.99999 -3.750056)
			(stroke
				(width 0.1524)
				(type default)
			)
			(layer "F.SilkS")
		)
		(fp_line
			(start 4.99999 -3.750056)
			(end 4.99999 -2.2479)
			(stroke
				(width 0.1524)
				(type default)
			)
			(layer "F.SilkS")
		)
		(fp_line
			(start -4.99999 3.750056)
			(end -4.99999 -3.750056)
			(stroke
				(width 0.1)
				(type default)
			)
			(layer "F.Fab")
		)
		(fp_line
			(start 0 3.750056)
			(end -4.99999 3.750056)
			(stroke
				(width 0.1)
				(type default)
			)
			(layer "F.Fab")
		)
		(fp_line
			(start 4.99999 3.750056)
			(end 0 3.750056)
			(stroke
				(width 0.1)
				(type default)
			)
			(layer "F.Fab")
		)
		(fp_line
			(start -4.99999 -3.750056)
			(end 4.99999 -3.750056)
			(stroke
				(width 0.1)
				(type default)
			)
			(layer "F.Fab")
		)
		(fp_line
			(start 4.99999 -3.750056)
			(end 4.99999 3.750056)
			(stroke
				(width 0.1)
				(type default)
			)
			(layer "F.Fab")
		)
		(pad "1" smd rect
			(at -3.299968 0 270)
			(size 3.302 4.2164)
			(layers "F.Cu" "F.Mask" "F.Paste")
			(net "SW_PVCCFA_EHV_FIVRA_CPU1_SW3")
		)
		(pad "2" smd rect
			(at 3.299968 0 270)
			(size 3.302 4.2164)
			(layers "F.Cu" "F.Mask" "F.Paste")
			(net "PVCCFA_EHV_FIVRA_CPU1")
		)
	)
)
